(kicad_pcb
	(version 20260206)
	(generator "pcbnew")
	(generator_version "10.0")
	(general
		(thickness 1.6)
		(legacy_teardrops no)
	)
	(paper "A4")
	(title_block
		(title "Wiwynn_Tioga_Pass_MB.brd")
		(comment 1 "Tioga Pass / footprints 618-624 of 4770")
	)
	(layers
		(0 "F.Cu" signal "TOP")
		(4 "In1.Cu" signal "L2GND")
		(6 "In2.Cu" signal "L3")
		(8 "In3.Cu" signal "L4GND")
		(10 "In4.Cu" signal "L5")
		(12 "In5.Cu" signal "L6GND")
		(14 "In6.Cu" signal "L7VCC")
		(16 "In7.Cu" signal "L8VCC")
		(18 "In8.Cu" signal "L9GND")
		(20 "In9.Cu" signal "L10")
		(22 "In10.Cu" signal "L11GND")
		(24 "In11.Cu" signal "L12")
		(26 "In12.Cu" signal "L13GND")
		(2 "B.Cu" signal "BOTTOM")
		(9 "F.Adhes" user "F.Adhesive")
		(11 "B.Adhes" user "B.Adhesive")
		(13 "F.Paste" user "Package Geometry/Pastemask Top")
		(15 "B.Paste" user "Package Geometry/Pastemask Bottom")
		(5 "F.SilkS" user "Ref Des/Silkscreen Top")
		(7 "B.SilkS" user "Ref Des/Silkscreen Bottom")
		(1 "F.Mask" user "Board Geometry/Soldermask Top")
		(3 "B.Mask" user "Board Geometry/Soldermask Bottom")
		(17 "Dwgs.User" user "User.Drawings")
		(19 "Cmts.User" user "User.Comments")
		(21 "Eco1.User" user "User.Eco1")
		(23 "Eco2.User" user "User.Eco2")
		(25 "Edge.Cuts" user "Board Geometry/Outline")
		(27 "Margin" user)
		(31 "F.CrtYd" user "Package Geometry/Place Bound Top")
		(29 "B.CrtYd" user "Package Geometry/Place Bound Bottom")
		(35 "F.Fab" user "Ref Des/Assembly Top")
		(33 "B.Fab" user "Ref Des/Assembly Bottom")
	)
	(footprint ""
		(layer "F.Cu")
		(at 379.2982 -29.232352 -90)
		(property "Reference" "R8F18"
			(at 0 0 270)
			(layer "F.SilkS")
			(hide yes)
			(effects
				(font
					(size 1.27 1.27)
				)
			)
		)
		(property "Value" ""
			(at 0 0 270)
			(layer "F.Fab")
			(effects
				(font
					(size 1.27 1.27)
				)
			)
		)
		(duplicate_pad_numbers_are_jumpers no)
		(fp_poly
			(pts
				(xy -0.2794 -0.1016) (xy 0.2794 -0.1016) (xy 0.2794 0.9906) (xy -0.2794 0.9906)
			)
			(stroke
				(width 0)
				(type default)
			)
			(fill no)
			(layer "F.CrtYd")
		)
		(fp_line
			(start -0.2794 0.9906)
			(end 0.2794 0.9906)
			(stroke
				(width 0.1)
				(type default)
			)
			(layer "F.Fab")
		)
		(fp_line
			(start 0.2794 0.9906)
			(end 0.2794 -0.1016)
			(stroke
				(width 0.1)
				(type default)
			)
			(layer "F.Fab")
		)
		(fp_line
			(start -0.2794 -0.1016)
			(end -0.2794 0.9906)
			(stroke
				(width 0.1)
				(type default)
			)
			(layer "F.Fab")
		)
		(fp_line
			(start 0.2794 -0.1016)
			(end -0.2794 -0.1016)
			(stroke
				(width 0.1)
				(type default)
			)
			(layer "F.Fab")
		)
		(pad "1" smd rect
			(at 0 0 270)
			(size 0.508 0.508)
			(layers "F.Cu" "F.Mask" "F.Paste")
			(net "P3E_PCH_RX_0_DP")
		)
		(pad "2" smd rect
			(at 0 0.889 270)
			(size 0.508 0.508)
			(layers "F.Cu" "F.Mask" "F.Paste")
			(net "P3E_PCH_M2_SATA6G_RX_R_DP")
		)
		(zone
			(layer "F.Cu")
			(hatch none 0.5)
			(connect_pads
				(clearance 0)
			)
			(min_thickness 0.25)
			(keepout
				(tracks not_allowed)
				(vias allowed)
				(pads allowed)
				(copperpour not_allowed)
				(footprints allowed)
			)
			(placement
				(enabled no)
				(sheetname "")
			)
			(fill
				(thermal_gap 0.5)
				(thermal_bridge_width 0.5)
				(island_removal_mode 0)
			)
			(polygon
				(pts
					(xy 378.6632 -29.486352) (xy 378.6632 -28.978352) (xy 379.0442 -28.978352) (xy 379.0442 -29.486352)
				)
			)
		)
		(zone
			(layer "F.Cu")
			(hatch none 0.5)
			(connect_pads
				(clearance 0)
			)
			(min_thickness 0.25)
			(keepout
				(tracks allowed)
				(vias not_allowed)
				(pads allowed)
				(copperpour not_allowed)
				(footprints allowed)
			)
			(placement
				(enabled no)
				(sheetname "")
			)
			(fill
				(thermal_gap 0.5)
				(thermal_bridge_width 0.5)
				(island_removal_mode 0)
			)
			(polygon
				(pts
					(xy 379.0442 -29.486352) (xy 379.0442 -28.978352) (xy 378.6632 -28.978352) (xy 378.6632 -29.486352)
				)
			)
		)
	)
	(footprint ""
		(layer "F.Cu")
		(at 173.093888 -10.255504 -90)
		(property "Reference" "R4G24"
			(at 1.01473 0.656336 180)
			(unlocked yes)
			(layer "F.SilkS")
			(effects
				(font
					(size 0.4064 0.254)
					(thickness 0.1524)
				)
			)
		)
		(property "Value" ""
			(at 0 0 270)
			(layer "F.Fab")
			(effects
				(font
					(size 1.27 1.27)
				)
			)
		)
		(duplicate_pad_numbers_are_jumpers no)
		(fp_poly
			(pts
				(xy -0.4953 -0.2032) (xy 0.4953 -0.2032) (xy 0.4953 1.6002) (xy -0.4953 1.6002)
			)
			(stroke
				(width 0)
				(type default)
			)
			(fill no)
			(layer "F.CrtYd")
		)
		(fp_line
			(start -0.4953 1.6002)
			(end -0.4953 -0.2032)
			(stroke
				(width 0.1)
				(type default)
			)
			(layer "F.Fab")
		)
		(fp_line
			(start 0.4953 1.6002)
			(end -0.4953 1.6002)
			(stroke
				(width 0.1)
				(type default)
			)
			(layer "F.Fab")
		)
		(fp_line
			(start -0.4953 -0.2032)
			(end 0.4953 -0.2032)
			(stroke
				(width 0.1)
				(type default)
			)
			(layer "F.Fab")
		)
		(fp_line
			(start 0.4953 -0.2032)
			(end 0.4953 1.6002)
			(stroke
				(width 0.1)
				(type default)
			)
			(layer "F.Fab")
		)
		(pad "1" smd rect
			(at 0 0 270)
			(size 0.762 0.889)
			(layers "F.Cu" "F.Mask" "F.Paste")
			(net "VR_PVPP_GHJ_BOOT")
		)
		(pad "2" smd rect
			(at 0 1.397 270)
			(size 0.762 0.889)
			(layers "F.Cu" "F.Mask" "F.Paste")
			(net "VR_PVPP_GHJ_BOOT_R")
		)
		(zone
			(layer "F.Cu")
			(hatch none 0.5)
			(connect_pads
				(clearance 0)
			)
			(min_thickness 0.25)
			(keepout
				(tracks not_allowed)
				(vias allowed)
				(pads allowed)
				(copperpour not_allowed)
				(footprints allowed)
			)
			(placement
				(enabled no)
				(sheetname "")
			)
			(fill
				(thermal_gap 0.5)
				(thermal_bridge_width 0.5)
				(island_removal_mode 0)
			)
			(polygon
				(pts
					(xy 172.141388 -10.636504) (xy 172.141388 -9.874504) (xy 172.649388 -9.874504) (xy 172.649388 -10.636504)
				)
			)
		)
		(zone
			(layer "F.Cu")
			(hatch none 0.5)
			(connect_pads
				(clearance 0)
			)
			(min_thickness 0.25)
			(keepout
				(tracks allowed)
				(vias not_allowed)
				(pads allowed)
				(copperpour not_allowed)
				(footprints allowed)
			)
			(placement
				(enabled no)
				(sheetname "")
			)
			(fill
				(thermal_gap 0.5)
				(thermal_bridge_width 0.5)
				(island_removal_mode 0)
			)
			(polygon
				(pts
					(xy 172.141388 -9.874504) (xy 172.649388 -9.874504) (xy 172.649388 -10.636504) (xy 172.141388 -10.636504)
				)
			)
		)
	)
	(footprint ""
		(layer "F.Cu")
		(at 383.032 -87.3125 180)
		(property "Reference" "R7D8"
			(at 0 0 180)
			(layer "F.SilkS")
			(hide yes)
			(effects
				(font
					(size 1.27 1.27)
				)
			)
		)
		(property "Value" ""
			(at 0 0 180)
			(layer "F.Fab")
			(effects
				(font
					(size 1.27 1.27)
				)
			)
		)
		(duplicate_pad_numbers_are_jumpers no)
		(fp_poly
			(pts
				(xy -0.2794 -0.1016) (xy 0.2794 -0.1016) (xy 0.2794 0.9906) (xy -0.2794 0.9906)
			)
			(stroke
				(width 0)
				(type default)
			)
			(fill no)
			(layer "F.CrtYd")
		)
		(fp_line
			(start 0.2794 0.9906)
			(end 0.2794 -0.1016)
			(stroke
				(width 0.1)
				(type default)
			)
			(layer "F.Fab")
		)
		(fp_line
			(start 0.2794 -0.1016)
			(end -0.2794 -0.1016)
			(stroke
				(width 0.1)
				(type default)
			)
			(layer "F.Fab")
		)
		(fp_line
			(start -0.2794 0.9906)
			(end 0.2794 0.9906)
			(stroke
				(width 0.1)
				(type default)
			)
			(layer "F.Fab")
		)
		(fp_line
			(start -0.2794 -0.1016)
			(end -0.2794 0.9906)
			(stroke
				(width 0.1)
				(type default)
			)
			(layer "F.Fab")
		)
		(pad "1" smd rect
			(at 0 0 180)
			(size 0.508 0.508)
			(layers "F.Cu" "F.Mask" "F.Paste")
			(net "P3V3_STBY")
		)
		(pad "2" smd rect
			(at 0 0.889 180)
			(size 0.508 0.508)
			(layers "F.Cu" "F.Mask" "F.Paste")
			(net "PU_LPC_CLKRUN_N")
		)
		(zone
			(layer "F.Cu")
			(hatch none 0.5)
			(connect_pads
				(clearance 0)
			)
			(min_thickness 0.25)
			(keepout
				(tracks not_allowed)
				(vias allowed)
				(pads allowed)
				(copperpour not_allowed)
				(footprints allowed)
			)
			(placement
				(enabled no)
				(sheetname "")
			)
			(fill
				(thermal_gap 0.5)
				(thermal_bridge_width 0.5)
				(island_removal_mode 0)
			)
			(polygon
				(pts
					(xy 383.286 -87.9475) (xy 382.778 -87.9475) (xy 382.778 -87.5665) (xy 383.286 -87.5665)
				)
			)
		)
		(zone
			(layer "F.Cu")
			(hatch none 0.5)
			(connect_pads
				(clearance 0)
			)
			(min_thickness 0.25)
			(keepout
				(tracks allowed)
				(vias not_allowed)
				(pads allowed)
				(copperpour not_allowed)
				(footprints allowed)
			)
			(placement
				(enabled no)
				(sheetname "")
			)
			(fill
				(thermal_gap 0.5)
				(thermal_bridge_width 0.5)
				(island_removal_mode 0)
			)
			(polygon
				(pts
					(xy 383.286 -87.5665) (xy 382.778 -87.5665) (xy 382.778 -87.9475) (xy 383.286 -87.9475)
				)
			)
		)
	)
	(footprint ""
		(layer "F.Cu")
		(at 408.673046 -107.434634 -90)
		(property "Reference" "R2P22"
			(at -0.8382 -0.849376 270)
			(unlocked yes)
			(layer "F.SilkS")
			(effects
				(font
					(size 0.7874 0.5842)
					(thickness 0.1524)
				)
				(justify left)
			)
		)
		(property "Value" ""
			(at 0 0 270)
			(layer "F.Fab")
			(effects
				(font
					(size 1.27 1.27)
				)
			)
		)
		(duplicate_pad_numbers_are_jumpers no)
		(fp_poly
			(pts
				(xy -0.2794 -0.1016) (xy 0.2794 -0.1016) (xy 0.2794 0.9906) (xy -0.2794 0.9906)
			)
			(stroke
				(width 0)
				(type default)
			)
			(fill no)
			(layer "F.CrtYd")
		)
		(fp_line
			(start -0.2794 0.9906)
			(end 0.2794 0.9906)
			(stroke
				(width 0.1)
				(type default)
			)
			(layer "F.Fab")
		)
		(fp_line
			(start 0.2794 0.9906)
			(end 0.2794 -0.1016)
			(stroke
				(width 0.1)
				(type default)
			)
			(layer "F.Fab")
		)
		(fp_line
			(start -0.2794 -0.1016)
			(end -0.2794 0.9906)
			(stroke
				(width 0.1)
				(type default)
			)
			(layer "F.Fab")
		)
		(fp_line
			(start 0.2794 -0.1016)
			(end -0.2794 -0.1016)
			(stroke
				(width 0.1)
				(type default)
			)
			(layer "F.Fab")
		)
		(pad "1" smd rect
			(at 0 0 270)
			(size 0.508 0.508)
			(layers "F.Cu" "F.Mask" "F.Paste")
			(net "P3V3_STBY")
		)
		(pad "2" smd rect
			(at 0 0.889 270)
			(size 0.508 0.508)
			(layers "F.Cu" "F.Mask" "F.Paste")
			(net "FM_CPU1_RC_EN")
		)
		(zone
			(layer "F.Cu")
			(hatch none 0.5)
			(connect_pads
				(clearance 0)
			)
			(min_thickness 0.25)
			(keepout
				(tracks not_allowed)
				(vias allowed)
				(pads allowed)
				(copperpour not_allowed)
				(footprints allowed)
			)
			(placement
				(enabled no)
				(sheetname "")
			)
			(fill
				(thermal_gap 0.5)
				(thermal_bridge_width 0.5)
				(island_removal_mode 0)
			)
			(polygon
				(pts
					(xy 408.038046 -107.688634) (xy 408.038046 -107.180634) (xy 408.419046 -107.180634) (xy 408.419046 -107.688634)
				)
			)
		)
		(zone
			(layer "F.Cu")
			(hatch none 0.5)
			(connect_pads
				(clearance 0)
			)
			(min_thickness 0.25)
			(keepout
				(tracks allowed)
				(vias not_allowed)
				(pads allowed)
				(copperpour not_allowed)
				(footprints allowed)
			)
			(placement
				(enabled no)
				(sheetname "")
			)
			(fill
				(thermal_gap 0.5)
				(thermal_bridge_width 0.5)
				(island_removal_mode 0)
			)
			(polygon
				(pts
					(xy 408.419046 -107.688634) (xy 408.419046 -107.180634) (xy 408.038046 -107.180634) (xy 408.038046 -107.688634)
				)
			)
		)
	)
	(footprint ""
		(layer "F.Cu")
		(at 264.7696 -84.7598)
		(property "Reference" "C5D6"
			(at 0 0 0)
			(layer "F.SilkS")
			(hide yes)
			(effects
				(font
					(size 1.27 1.27)
				)
			)
		)
		(property "Value" ""
			(at 0 0 0)
			(layer "F.Fab")
			(effects
				(font
					(size 1.27 1.27)
				)
			)
		)
		(duplicate_pad_numbers_are_jumpers no)
		(fp_poly
			(pts
				(xy -0.4953 -0.2032) (xy 0.4953 -0.2032) (xy 0.4953 1.6002) (xy -0.4953 1.6002)
			)
			(stroke
				(width 0)
				(type default)
			)
			(fill no)
			(layer "F.CrtYd")
		)
		(fp_line
			(start -0.4953 -0.2032)
			(end 0.4953 -0.2032)
			(stroke
				(width 0.1)
				(type default)
			)
			(layer "F.Fab")
		)
		(fp_line
			(start -0.4953 1.6002)
			(end -0.4953 -0.2032)
			(stroke
				(width 0.1)
				(type default)
			)
			(layer "F.Fab")
		)
		(fp_line
			(start 0.4953 -0.2032)
			(end 0.4953 1.6002)
			(stroke
				(width 0.1)
				(type default)
			)
			(layer "F.Fab")
		)
		(fp_line
			(start 0.4953 1.6002)
			(end -0.4953 1.6002)
			(stroke
				(width 0.1)
				(type default)
			)
			(layer "F.Fab")
		)
		(pad "1" smd rect
			(at 0 0)
			(size 0.762 0.889)
			(layers "F.Cu" "F.Mask" "F.Paste")
			(net "PVDDQ_DEF")
		)
		(pad "2" smd rect
			(at 0 1.397)
			(size 0.762 0.889)
			(layers "F.Cu" "F.Mask" "F.Paste")
			(net "GND")
		)
		(zone
			(layer "F.Cu")
			(hatch none 0.5)
			(connect_pads
				(clearance 0)
			)
			(min_thickness 0.25)
			(keepout
				(tracks not_allowed)
				(vias allowed)
				(pads allowed)
				(copperpour not_allowed)
				(footprints allowed)
			)
			(placement
				(enabled no)
				(sheetname "")
			)
			(fill
				(thermal_gap 0.5)
				(thermal_bridge_width 0.5)
				(island_removal_mode 0)
			)
			(polygon
				(pts
					(xy 264.3886 -84.3153) (xy 265.1506 -84.3153) (xy 265.1506 -83.8073) (xy 264.3886 -83.8073)
				)
			)
		)
	)
	(footprint ""
		(layer "F.Cu")
		(at 362.593382 -147.15871 180)
		(property "Reference" "L7A5"
			(at 0 0 180)
			(layer "F.SilkS")
			(hide yes)
			(effects
				(font
					(size 1.27 1.27)
				)
			)
		)
		(property "Value" "*"
			(at -3.5941 0.3429 180)
			(unlocked yes)
			(layer "F.Fab")
			(hide yes)
			(effects
				(font
					(size 1.27 1.016)
					(thickness 0.1524)
				)
			)
		)
		(property "Device Type" "IND-100NH-35-GP_DISCRET-G8-INDA"
			(at -3.5941 -1.1811 180)
			(unlocked yes)
			(layer "F.Fab")
			(hide yes)
			(effects
				(font
					(size 1.27 1.016)
					(thickness 0.1524)
				)
			)
		)
		(duplicate_pad_numbers_are_jumpers no)
		(fp_line
			(start 2.2479 2.794)
			(end -2.2479 2.794)
			(stroke
				(width 0.1524)
				(type default)
			)
			(layer "F.SilkS")
		)
		(fp_line
			(start 2.2479 -2.794)
			(end 2.2479 2.794)
			(stroke
				(width 0.1524)
				(type default)
			)
			(layer "F.SilkS")
		)
		(fp_line
			(start -2.2479 2.794)
			(end -2.2479 -2.794)
			(stroke
				(width 0.1524)
				(type default)
			)
			(layer "F.SilkS")
		)
		(fp_line
			(start -2.2479 -2.794)
			(end 2.2479 -2.794)
			(stroke
				(width 0.1524)
				(type default)
			)
			(layer "F.SilkS")
		)
		(fp_rect
			(start -1.9939 1.9939)
			(end 1.9939 -1.9939)
			(stroke
				(width 0)
				(type default)
			)
			(fill no)
			(layer "F.CrtYd")
		)
		(fp_poly
			(pts
				(xy -2.5019 2.8702) (xy -2.5019 1.9939) (xy 1.9939 1.9939) (xy 1.9939 -1.9939) (xy -1.9939 -1.9939)
				(xy -1.9939 1.9812) (xy -2.5019 1.9812) (xy -2.5019 -2.8702) (xy 2.5019 -2.8702) (xy 2.5019 2.8702)
			)
			(stroke
				(width 0)
				(type default)
			)
			(fill no)
			(layer "F.CrtYd")
		)
		(fp_rect
			(start -2.5019 2.8702)
			(end 2.5019 -2.8702)
			(stroke
				(width 0)
				(type default)
			)
			(fill no)
			(layer "F.Fab")
		)
		(pad "1" smd rect
			(at 0 -1.745996 180)
			(size 1.5494 1.6002)
			(layers "F.Cu" "F.Mask" "F.Paste")
			(net "P12V_STBY")
		)
		(pad "2" smd rect
			(at 0 1.745996 180)
			(size 1.5494 1.6002)
			(layers "F.Cu" "F.Mask" "F.Paste")
			(net "VR_FET_SW_P12V_STBY_PVDDQ_DEF")
		)
	)
	(footprint ""
		(layer "F.Cu")
		(at 112.4458 -69.85)
		(property "Reference" "R3D26"
			(at 0 0 0)
			(layer "F.SilkS")
			(hide yes)
			(effects
				(font
					(size 1.27 1.27)
				)
			)
		)
		(property "Value" ""
			(at 0 0 0)
			(layer "F.Fab")
			(effects
				(font
					(size 1.27 1.27)
				)
			)
		)
		(duplicate_pad_numbers_are_jumpers no)
		(fp_poly
			(pts
				(xy -0.2794 -0.1016) (xy 0.2794 -0.1016) (xy 0.2794 0.9906) (xy -0.2794 0.9906)
			)
			(stroke
				(width 0)
				(type default)
			)
			(fill no)
			(layer "F.CrtYd")
		)
		(fp_line
			(start -0.2794 -0.1016)
			(end -0.2794 0.9906)
			(stroke
				(width 0.1)
				(type default)
			)
			(layer "F.Fab")
		)
		(fp_line
			(start -0.2794 0.9906)
			(end 0.2794 0.9906)
			(stroke
				(width 0.1)
				(type default)
			)
			(layer "F.Fab")
		)
		(fp_line
			(start 0.2794 -0.1016)
			(end -0.2794 -0.1016)
			(stroke
				(width 0.1)
				(type default)
			)
			(layer "F.Fab")
		)
		(fp_line
			(start 0.2794 0.9906)
			(end 0.2794 -0.1016)
			(stroke
				(width 0.1)
				(type default)
			)
			(layer "F.Fab")
		)
		(pad "1" smd rect
			(at 0 0)
			(size 0.508 0.508)
			(layers "F.Cu" "F.Mask" "F.Paste")
			(net "PVCCIO_CPU1")
		)
		(pad "2" smd rect
			(at 0 0.889)
			(size 0.508 0.508)
			(layers "F.Cu" "F.Mask" "F.Paste")
			(net "PU_CPU1_SAFE_MODE_BOOT")
		)
		(zone
			(layer "F.Cu")
			(hatch none 0.5)
			(connect_pads
				(clearance 0)
			)
			(min_thickness 0.25)
			(keepout
				(tracks allowed)
				(vias not_allowed)
				(pads allowed)
				(copperpour not_allowed)
				(footprints allowed)
			)
			(placement
				(enabled no)
				(sheetname "")
			)
			(fill
				(thermal_gap 0.5)
				(thermal_bridge_width 0.5)
				(island_removal_mode 0)
			)
			(polygon
				(pts
					(xy 112.1918 -69.596) (xy 112.6998 -69.596) (xy 112.6998 -69.215) (xy 112.1918 -69.215)
				)
			)
		)
		(zone
			(layer "F.Cu")
			(hatch none 0.5)
			(connect_pads
				(clearance 0)
			)
			(min_thickness 0.25)
			(keepout
				(tracks not_allowed)
				(vias allowed)
				(pads allowed)
				(copperpour not_allowed)
				(footprints allowed)
			)
			(placement
				(enabled no)
				(sheetname "")
			)
			(fill
				(thermal_gap 0.5)
				(thermal_bridge_width 0.5)
				(island_removal_mode 0)
			)
			(polygon
				(pts
					(xy 112.1918 -69.215) (xy 112.6998 -69.215) (xy 112.6998 -69.596) (xy 112.1918 -69.596)
				)
			)
		)
	)
)
